# T6G (Grand Teton) — schematic netlist excerpt (pin names and nets, part order shuffled) for the footprints in the layout excerpt that follows; sources: Cadence DE-HDL packaged netlist, KiCad conversion of 04192023_DAF0TMB3IC0_F0TG_MB_C_brd_V02_OCP.brd

J21  SCONN288_DDR506112002KQ  IO  pkg DDR288S_1-1VXC  page 90
  VIN_BULK0  = P12V_MEM_CPU0
  RFU0  = NC
  VIN_MGMT  = P3V3_AUX
  HSCL  = I3C_SPD_DDRE_CPU0_SCL
  HSDA  = I3C_SPD_DDRE_CPU0_SDA
  VSS0  = GND
  DQ0_A  = M_E_CPU0_SA_DQ<0>
  VSS1  = GND
  DQ1_A  = M_E_CPU0_SA_DQ<1>
  VSS2  = GND
  DQS0_A_T  = M_E_CPU0_SA_DQS_DP<0>
  DQS0_A_C  = M_E_CPU0_SA_DQS_DN<0>
  VSS3  = GND
  DQ4_A  = M_E_CPU0_SA_DQ<4>
  VSS4  = GND
  DQ5_A  = M_E_CPU0_SA_DQ<5>
  VSS5  = GND
  DQ8_A  = M_E_CPU0_SA_DQ<8>
  VSS6  = GND
  DQ9_A  = M_E_CPU0_SA_DQ<9>
  VSS7  = GND
  DQS1_A_T  = M_E_CPU0_SA_DQS_DP<1>
  DQS1_A_C  = M_E_CPU0_SA_DQS_DN<1>
  VSS8  = GND
  DQ12_A  = M_E_CPU0_SA_DQ<12>
  VSS9  = GND
  DQ13_A  = M_E_CPU0_SA_DQ<13>
  VSS10  = GND
  DQ16_A  = M_E_CPU0_SA_DQ<16>
  VSS11  = GND
  DQ17_A  = M_E_CPU0_SA_DQ<17>
  VSS12  = GND
  DQS2_A_T  = M_E_CPU0_SA_DQS_DP<2>
  DQS2_A_C  = M_E_CPU0_SA_DQS_DN<2>
  VSS13  = GND
  DQ20_A  = M_E_CPU0_SA_DQ<20>
  VSS14  = GND
  DQ21_A  = M_E_CPU0_SA_DQ<21>
  VSS15  = GND
  DQ24_A  = M_E_CPU0_SA_DQ<24>
  VSS16  = GND
  DQ25_A  = M_E_CPU0_SA_DQ<25>
  VSS17  = GND
  DQS3_A_T  = M_E_CPU0_SA_DQS_DP<3>
  DQS3_A_C  = M_E_CPU0_SA_DQS_DN<3>
  VSS18  = GND
  DQ28_A  = M_E_CPU0_SA_DQ<28>
  VSS19  = GND
  DQ29_A  = M_E_CPU0_SA_DQ<29>
  VSS20  = GND
  CB0_A  = M_E_CPU0_SA_CB<0>
  VSS21  = GND
  CB1_A  = M_E_CPU0_SA_CB<1>
  VSS22  = GND
  DQS4_A_T  = M_E_CPU0_SA_DQS_DP<4>
  DQS4_A_C  = M_E_CPU0_SA_DQS_DN<4>
  VSS23  = GND
  CB4_A  = M_E_CPU0_SA_CB<4>
  VSS24  = GND
  CB5_A  = M_E_CPU0_SA_CB<5>
  VSS25  = GND
  ALERT_N  = M_E_CPU0_ALERT_N
  VSS26  = GND
  CS0_A_N  = M_E_CPU0_SA_CS_N<0>
  VSS27  = GND
  CA0_A  = M_E_CPU0_SA_CA<0>
  VSS28  = GND
  CA2_A  = M_E_CPU0_SA_CA<2>
  VSS29  = GND
  CA4_A  = M_E_CPU0_SA_CA<4>
  VSS30  = GND
  CA6_A  = M_E_CPU0_SA_CA<6>
  VSS31  = GND
  PAR_A  = M_E_CPU0_SA_PAR
  VSS32  = GND
  CA0_B  = M_E_CPU0_SB_CA<0>
  VSS33  = GND
  CA2_B  = M_E_CPU0_SB_CA<2>
  VSS34  = GND
  CA4_B  = M_E_CPU0_SB_CA<4>
  VSS35  = GND
  CA6_B  = M_E_CPU0_SB_CA<6>
  VSS36  = GND
  CS0_B_N  = M_E_CPU0_SB_CS_N<0>
  VSS37  = GND
  \lbd||rsp_a_n\  = M_E_CPU0_SA_RSP<0>
  \lbs||rsp_b_n\  = M_E_CPU0_SB_RSP<0>
  VSS38  = GND
  CB4_B  = M_E_CPU0_SB_CB<4>
  VSS39  = GND
  CB5_B  = M_E_CPU0_SB_CB<5>
  VSS40  = GND
  \dqs9_b_t||tdqs9_b_t||dbi4_b_n\  = M_E_CPU0_SB_DQS_DP<9>
  \dqs9_b_c||tdqs9_b_c\  = M_E_CPU0_SB_DQS_DN<9>
  VSS41  = GND
  CB0_B  = M_E_CPU0_SB_CB<0>
  VSS42  = GND
  CB1_B  = M_E_CPU0_SB_CB<1>
  VSS43  = GND
  DQ0_B  = M_E_CPU0_SB_DQ<0>
  VSS44  = GND
  DQ1_B  = M_E_CPU0_SB_DQ<1>
  VSS45  = GND
  DQS0_B_T  = M_E_CPU0_SB_DQS_DP<0>
  DQS0_B_C  = M_E_CPU0_SB_DQS_DN<0>
  VSS46  = GND
  DQ4_B  = M_E_CPU0_SB_DQ<4>
  VSS47  = GND
  DQ5_B  = M_E_CPU0_SB_DQ<5>
  VSS48  = GND
  DQ8_B  = M_E_CPU0_SB_DQ<8>
  VSS49  = GND
  DQ9_B  = M_E_CPU0_SB_DQ<9>
  VSS50  = GND
  DQS1_B_T  = M_E_CPU0_SB_DQS_DP<1>
  DQS1_B_C  = M_E_CPU0_SB_DQS_DN<1>
  VSS51  = GND
  DQ12_B  = M_E_CPU0_SB_DQ<12>
  VSS52  = GND
  DQ13_B  = M_E_CPU0_SB_DQ<13>
  VSS53  = GND
  DQ16_B  = M_E_CPU0_SB_DQ<16>
  VSS54  = GND
  DQ17_B  = M_E_CPU0_SB_DQ<17>
  VSS55  = GND
  DQS2_B_T  = M_E_CPU0_SB_DQS_DP<2>
  DQS2_B_C  = M_E_CPU0_SB_DQS_DN<2>
  VSS56  = GND
  DQ20_B  = M_E_CPU0_SB_DQ<20>
  VSS57  = GND
  DQ21_B  = M_E_CPU0_SB_DQ<21>
  VSS58  = GND
  DQ24_B  = M_E_CPU0_SB_DQ<24>
  VSS59  = GND
  DQ25_B  = M_E_CPU0_SB_DQ<25>
  VSS60  = GND
  DQS3_B_T  = M_E_CPU0_SB_DQS_DP<3>
  DQS3_B_C  = M_E_CPU0_SB_DQS_DN<3>
  VSS61  = GND
  DQ28_B  = M_E_CPU0_SB_DQ<28>
  VSS62  = GND
  DQ29_B  = M_E_CPU0_SB_DQ<29>
  VSS63  = GND
  RFU1  = NC
  VIN_BULK1  = P12V_MEM_CPU0
  VIN_BULK2  = P12V_MEM_CPU0
  \pwr_good||fail_n\  = PWRGD_CHE_CPU0_DIMM
  HAS  = PD_CHE_CPU0_DIMM_SAA
  RFU2  = NC
  RFU3  = NC
  VSS64  = GND
  DQ2_A  = M_E_CPU0_SA_DQ<2>
  VSS65  = GND
  DQ3_A  = M_E_CPU0_SA_DQ<3>
  VSS66  = GND
  \dqs5_a_c||tdqs5_a_c||dqs5_a_t||tdqs5_a_t\  = M_E_CPU0_SA_DQS_DN<5>
  \dqs5_a_t||tdqs5_a_t\  = M_E_CPU0_SA_DQS_DP<5>
  VSS67  = GND
  DQ6_A  = M_E_CPU0_SA_DQ<6>
  VSS68  = GND
  DQ7_A  = M_E_CPU0_SA_DQ<7>
  VSS69  = GND
  DQ10_A  = M_E_CPU0_SA_DQ<10>
  VSS70  = GND
  DQ11_A  = M_E_CPU0_SA_DQ<11>
  VSS71  = GND
  \dqs6_a_c||tdqs6_a_c||dqs6_a_t||tdqs6_a_t\  = M_E_CPU0_SA_DQS_DN<6>
  \dqs6_a_t||tdqs6_a_t\  = M_E_CPU0_SA_DQS_DP<6>
  VSS72  = GND
  DQ14_A  = M_E_CPU0_SA_DQ<14>
  VSS73  = GND
  DQ15_A  = M_E_CPU0_SA_DQ<15>
  VSS74  = GND
  DQ18_A  = M_E_CPU0_SA_DQ<18>
  VSS75  = GND
  DQ19_A  = M_E_CPU0_SA_DQ<19>
  VSS76  = GND
  \dqs7_a_c||tdqs7_a_c\  = M_E_CPU0_SA_DQS_DN<7>
  \dqs7_a_t||tdqs7_a_t\  = M_E_CPU0_SA_DQS_DP<7>
  VSS77  = GND
  DQ22_A  = M_E_CPU0_SA_DQ<22>
  VSS78  = GND
  DQ23_A  = M_E_CPU0_SA_DQ<23>
  VSS79  = GND
  DQ26_A  = M_E_CPU0_SA_DQ<26>
  VSS80  = GND
  DQ27_A  = M_E_CPU0_SA_DQ<27>
  VSS81  = GND
  \dqs8_a_c||tdqs8_a_c\  = M_E_CPU0_SA_DQS_DN<8>
  \dqs8_a_t||tdqs8_a_t\  = M_E_CPU0_SA_DQS_DP<8>
  VSS82  = GND
  DQ30_A  = M_E_CPU0_SA_DQ<30>
  VSS83  = GND
  DQ31_A  = M_E_CPU0_SA_DQ<31>
  VSS84  = GND
  CB2_A  = M_E_CPU0_SA_CB<2>
  VSS85  = GND
  CB3_A  = M_E_CPU0_SA_CB<3>
  VSS86  = GND
  \dqs9_a_c||tdqs9_a_c\  = M_E_CPU0_SA_DQS_DN<9>
  \dqs9_a_t||tdqs9_a_t\  = M_E_CPU0_SA_DQS_DP<9>
  VSS87  = GND
  CB6_A  = M_E_CPU0_SA_CB<6>
  VSS88  = GND
  CB7_A  = M_E_CPU0_SA_CB<7>
  VSS89  = GND
  RESET_N  = M_E_CPU0_RESET_N
  VSS90  = GND
  CS1_A_N  = M_E_CPU0_SA_CS_N<1>
  VSS91  = GND
  CA1_A  = M_E_CPU0_SA_CA<1>
  VSS92  = GND
  CA3_A  = M_E_CPU0_SA_CA<3>
  VSS93  = GND
  CA5_A  = M_E_CPU0_SA_CA<5>
  VSS94  = GND
  CK_T  = M_E_CPU0_CLK_DP<0>
  CK_C  = M_E_CPU0_CLK_DN<0>
  VSS95  = GND
  RFU4  = NC
  CA1_B  = M_E_CPU0_SB_CA<1>
  VSS96  = GND
  CA3_B  = M_E_CPU0_SB_CA<3>
  VSS97  = GND
  CA5_B  = M_E_CPU0_SB_CA<5>
  VSS98  = GND
  PAR_B  = M_E_CPU0_SB_PAR
  VSS99  = GND
  CS1_B_N  = M_E_CPU0_SB_CS_N<1>
  VSS100  = GND
  RFU5  = NC
  RFU6  = NC
  VSS101  = GND
  CB6_B  = M_E_CPU0_SB_CB<6>
  VSS102  = GND
  CB7_B  = M_E_CPU0_SB_CB<7>
  VSS103  = GND
  DQS4_B_C  = M_E_CPU0_SB_DQS_DN<4>
  DQS4_B_T  = M_E_CPU0_SB_DQS_DP<4>
  VSS104  = GND
  CB2_B  = M_E_CPU0_SB_CB<2>
  VSS105  = GND
  CB3_B  = M_E_CPU0_SB_CB<3>
  VSS106  = GND
  DQ2_B  = M_E_CPU0_SB_DQ<2>
  VSS107  = GND
  DQ3_B  = M_E_CPU0_SB_DQ<3>
  VSS108  = GND
  \dqs5_b_c||tdqs5_b_c\  = M_E_CPU0_SB_DQS_DN<5>
  \dqs5_b_t||tdqs5_b_t\  = M_E_CPU0_SB_DQS_DP<5>
  VSS109  = GND
  DQ6_B  = M_E_CPU0_SB_DQ<6>
  VSS110  = GND
  DQ7_B  = M_E_CPU0_SB_DQ<7>
  VSS111  = GND
  DQ10_B  = M_E_CPU0_SB_DQ<10>
  VSS112  = GND
  DQ11_B  = M_E_CPU0_SB_DQ<11>
  VSS113  = GND
  \dqs6_b_c||tdqs6_b_c\  = M_E_CPU0_SB_DQS_DN<6>
  \dqs6_b_t||tdqs6_b_t\  = M_E_CPU0_SB_DQS_DP<6>
  VSS114  = GND
  DQ14_B  = M_E_CPU0_SB_DQ<14>
  VSS115  = GND
  DQ15_B  = M_E_CPU0_SB_DQ<15>
  VSS116  = GND
  DQ18_B  = M_E_CPU0_SB_DQ<18>
  VSS117  = GND
  DQ19_B  = M_E_CPU0_SB_DQ<19>
  VSS118  = GND
  \dqs7_b_c||tdqs7_b_c\  = M_E_CPU0_SB_DQS_DN<7>
  \dqs7_b_t||tdqs7_b_t\  = M_E_CPU0_SB_DQS_DP<7>
  VSS119  = GND
  DQ22_B  = M_E_CPU0_SB_DQ<22>
  VSS120  = GND
  DQ23_B  = M_E_CPU0_SB_DQ<23>
  VSS121  = GND
  DQ26_B  = M_E_CPU0_SB_DQ<26>
  VSS122  = GND
  DQ27_B  = M_E_CPU0_SB_DQ<27>
  VSS123  = GND
  \dqs8_b_c||tdqs8_b_c\  = M_E_CPU0_SB_DQS_DN<8>
  \dqs8_b_t||tdqs8_b_t\  = M_E_CPU0_SB_DQS_DP<8>
  VSS124  = GND
  DQ30_B  = M_E_CPU0_SB_DQ<30>
  VSS125  = GND
  DQ31_B  = M_E_CPU0_SB_DQ<31>
  VSS126  = GND
  G1  = GND
  G2  = GND
  G3  = GND

(kicad_pcb
	(version 20260206)
	(generator "pcbnew")
	(generator_version "10.0")
	(general
		(thickness 1.6)
		(legacy_teardrops no)
	)
	(paper "A4")
	(title_block
		(title "04192023_DAF0TMB3IC0_F0TG_MB_C_brd_V02_OCP.brd")
		(comment 1 "Grand Teton / footprint 3 of 8354 (J21), pads 231-276 of 291")
	)
	(layers
		(0 "F.Cu" signal "TOP")
		(4 "In1.Cu" signal "GND")
		(6 "In2.Cu" signal "IN1")
		(8 "In3.Cu" signal "GND1")
		(10 "In4.Cu" signal "IN2")
		(12 "In5.Cu" signal "GND2")
		(14 "In6.Cu" signal "IN3")
		(16 "In7.Cu" signal "GND3")
		(18 "In8.Cu" signal "VCC")
		(20 "In9.Cu" signal "VCC1")
		(22 "In10.Cu" signal "GND4")
		(24 "In11.Cu" signal "IN4")
		(26 "In12.Cu" signal "GND5")
		(28 "In13.Cu" signal "IN5")
		(30 "In14.Cu" signal "GND6")
		(32 "In15.Cu" signal "IN6")
		(34 "In16.Cu" signal "GND7")
		(2 "B.Cu" signal "BOTTOM")
		(9 "F.Adhes" user "F.Adhesive")
		(11 "B.Adhes" user "B.Adhesive")
		(13 "F.Paste" user "Package Geometry/Pastemask Top")
		(15 "B.Paste" user "Package Geometry/Pastemask Bottom")
		(5 "F.SilkS" user "Ref Des/Silkscreen Top")
		(7 "B.SilkS" user "Ref Des/Silkscreen Bottom")
		(1 "F.Mask" user "Board Geometry/Soldermask Top")
		(3 "B.Mask" user "Board Geometry/Soldermask Bottom")
		(17 "Dwgs.User" user "User.Drawings")
		(19 "Cmts.User" user "User.Comments")
		(21 "Eco1.User" user "User.Eco1")
		(23 "Eco2.User" user "User.Eco2")
		(25 "Edge.Cuts" user "Board Geometry/Outline")
		(27 "Margin" user)
		(31 "F.CrtYd" user "Package Geometry/Place Bound Top")
		(29 "B.CrtYd" user "Package Geometry/Place Bound Bottom")
		(35 "F.Fab" user "Ref Des/Assembly Top")
		(33 "B.Fab" user "Ref Des/Assembly Bottom")
	)
	(footprint ""
		(layer "F.Cu")
		(at 275.142198 -255.560068 180)
		(property "Reference" "J21"
			(at -2.2098 -81.984088 0)
			(unlocked yes)
			(layer "F.SilkS")
			(effects
				(font
					(size 0.7874 0.5842)
					(thickness 0.1524)
				)
			)
		)
		(property "Value" ""
			(at 0 0 180)
			(layer "F.Fab")
			(effects
				(font
					(size 1.27 1.27)
				)
			)
		)
		(duplicate_pad_numbers_are_jumpers no)
		(pad "231" smd rect
			(at 2.050034 14.875002 90)
			(size 0.519938 1.4986)
			(layers "F.Cu" "F.Mask" "F.Paste")
			(net "Net_2310")
		)
		(pad "232" smd rect
			(at 2.050034 15.724886 90)
			(size 0.519938 1.4986)
			(layers "F.Cu" "F.Mask" "F.Paste")
			(net "Net_2311")
		)
		(pad "233" smd rect
			(at 2.050034 16.575024 90)
			(size 0.519938 1.4986)
			(layers "F.Cu" "F.Mask" "F.Paste")
			(net "GND")
		)
		(pad "234" smd rect
			(at 2.050034 17.424908 90)
			(size 0.519938 1.4986)
			(layers "F.Cu" "F.Mask" "F.Paste")
			(net "M_E_CPU0_SB_CB<6>")
		)
		(pad "235" smd rect
			(at 2.050034 18.275046 90)
			(size 0.519938 1.4986)
			(layers "F.Cu" "F.Mask" "F.Paste")
			(net "GND")
		)
		(pad "236" smd rect
			(at 2.050034 19.12493 90)
			(size 0.519938 1.4986)
			(layers "F.Cu" "F.Mask" "F.Paste")
			(net "M_E_CPU0_SB_CB<7>")
		)
		(pad "237" smd rect
			(at 2.050034 19.975068 90)
			(size 0.519938 1.4986)
			(layers "F.Cu" "F.Mask" "F.Paste")
			(net "GND")
		)
		(pad "238" smd rect
			(at 2.050034 20.824952 90)
			(size 0.519938 1.4986)
			(layers "F.Cu" "F.Mask" "F.Paste")
			(net "M_E_CPU0_SB_DQS_DN<4>")
		)
		(pad "239" smd rect
			(at 2.050034 21.67509 90)
			(size 0.519938 1.4986)
			(layers "F.Cu" "F.Mask" "F.Paste")
			(net "M_E_CPU0_SB_DQS_DP<4>")
		)
		(pad "240" smd rect
			(at 2.050034 22.524974 90)
			(size 0.519938 1.4986)
			(layers "F.Cu" "F.Mask" "F.Paste")
			(net "GND")
		)
		(pad "241" smd rect
			(at 2.050034 23.375112 90)
			(size 0.519938 1.4986)
			(layers "F.Cu" "F.Mask" "F.Paste")
			(net "M_E_CPU0_SB_CB<2>")
		)
		(pad "242" smd rect
			(at 2.050034 24.224996 90)
			(size 0.519938 1.4986)
			(layers "F.Cu" "F.Mask" "F.Paste")
			(net "GND")
		)
		(pad "243" smd rect
			(at 2.050034 25.07488 90)
			(size 0.519938 1.4986)
			(layers "F.Cu" "F.Mask" "F.Paste")
			(net "M_E_CPU0_SB_CB<3>")
		)
		(pad "244" smd rect
			(at 2.050034 25.925018 90)
			(size 0.519938 1.4986)
			(layers "F.Cu" "F.Mask" "F.Paste")
			(net "GND")
		)
		(pad "245" smd rect
			(at 2.050034 26.774902 90)
			(size 0.519938 1.4986)
			(layers "F.Cu" "F.Mask" "F.Paste")
			(net "M_E_CPU0_SB_DQ<2>")
		)
		(pad "246" smd rect
			(at 2.050034 27.62504 90)
			(size 0.519938 1.4986)
			(layers "F.Cu" "F.Mask" "F.Paste")
			(net "GND")
		)
		(pad "247" smd rect
			(at 2.050034 28.474924 90)
			(size 0.519938 1.4986)
			(layers "F.Cu" "F.Mask" "F.Paste")
			(net "M_E_CPU0_SB_DQ<3>")
		)
		(pad "248" smd rect
			(at 2.050034 29.325062 90)
			(size 0.519938 1.4986)
			(layers "F.Cu" "F.Mask" "F.Paste")
			(net "GND")
		)
		(pad "249" smd rect
			(at 2.050034 30.174946 90)
			(size 0.519938 1.4986)
			(layers "F.Cu" "F.Mask" "F.Paste")
			(net "M_E_CPU0_SB_DQS_DN<5>")
		)
		(pad "250" smd rect
			(at 2.050034 31.025084 90)
			(size 0.519938 1.4986)
			(layers "F.Cu" "F.Mask" "F.Paste")
			(net "M_E_CPU0_SB_DQS_DP<5>")
		)
		(pad "251" smd rect
			(at 2.050034 31.874968 90)
			(size 0.519938 1.4986)
			(layers "F.Cu" "F.Mask" "F.Paste")
			(net "GND")
		)
		(pad "252" smd rect
			(at 2.050034 32.725106 90)
			(size 0.519938 1.4986)
			(layers "F.Cu" "F.Mask" "F.Paste")
			(net "M_E_CPU0_SB_DQ<6>")
		)
		(pad "253" smd rect
			(at 2.050034 33.57499 90)
			(size 0.519938 1.4986)
			(layers "F.Cu" "F.Mask" "F.Paste")
			(net "GND")
		)
		(pad "254" smd rect
			(at 2.050034 34.425128 90)
			(size 0.519938 1.4986)
			(layers "F.Cu" "F.Mask" "F.Paste")
			(net "M_E_CPU0_SB_DQ<7>")
		)
		(pad "255" smd rect
			(at 2.050034 35.275012 90)
			(size 0.519938 1.4986)
			(layers "F.Cu" "F.Mask" "F.Paste")
			(net "GND")
		)
		(pad "256" smd rect
			(at 2.050034 36.124896 90)
			(size 0.519938 1.4986)
			(layers "F.Cu" "F.Mask" "F.Paste")
			(net "M_E_CPU0_SB_DQ<10>")
		)
		(pad "257" smd rect
			(at 2.050034 36.975034 90)
			(size 0.519938 1.4986)
			(layers "F.Cu" "F.Mask" "F.Paste")
			(net "GND")
		)
		(pad "258" smd rect
			(at 2.050034 37.824918 90)
			(size 0.519938 1.4986)
			(layers "F.Cu" "F.Mask" "F.Paste")
			(net "M_E_CPU0_SB_DQ<11>")
		)
		(pad "259" smd rect
			(at 2.050034 38.675056 90)
			(size 0.519938 1.4986)
			(layers "F.Cu" "F.Mask" "F.Paste")
			(net "GND")
		)
		(pad "260" smd rect
			(at 2.050034 39.52494 90)
			(size 0.519938 1.4986)
			(layers "F.Cu" "F.Mask" "F.Paste")
			(net "M_E_CPU0_SB_DQS_DN<6>")
		)
		(pad "261" smd rect
			(at 2.050034 40.375078 90)
			(size 0.519938 1.4986)
			(layers "F.Cu" "F.Mask" "F.Paste")
			(net "M_E_CPU0_SB_DQS_DP<6>")
		)
		(pad "262" smd rect
			(at 2.050034 41.224962 90)
			(size 0.519938 1.4986)
			(layers "F.Cu" "F.Mask" "F.Paste")
			(net "GND")
		)
		(pad "263" smd rect
			(at 2.050034 42.0751 90)
			(size 0.519938 1.4986)
			(layers "F.Cu" "F.Mask" "F.Paste")
			(net "M_E_CPU0_SB_DQ<14>")
		)
		(pad "264" smd rect
			(at 2.050034 42.924984 90)
			(size 0.519938 1.4986)
			(layers "F.Cu" "F.Mask" "F.Paste")
			(net "GND")
		)
		(pad "265" smd rect
			(at 2.050034 43.775122 90)
			(size 0.519938 1.4986)
			(layers "F.Cu" "F.Mask" "F.Paste")
			(net "M_E_CPU0_SB_DQ<15>")
		)
		(pad "266" smd rect
			(at 2.050034 44.625006 90)
			(size 0.519938 1.4986)
			(layers "F.Cu" "F.Mask" "F.Paste")
			(net "GND")
		)
		(pad "267" smd rect
			(at 2.050034 45.47489 90)
			(size 0.519938 1.4986)
			(layers "F.Cu" "F.Mask" "F.Paste")
			(net "M_E_CPU0_SB_DQ<18>")
		)
		(pad "268" smd rect
			(at 2.050034 46.325028 90)
			(size 0.519938 1.4986)
			(layers "F.Cu" "F.Mask" "F.Paste")
			(net "GND")
		)
		(pad "269" smd rect
			(at 2.050034 47.174912 90)
			(size 0.519938 1.4986)
			(layers "F.Cu" "F.Mask" "F.Paste")
			(net "M_E_CPU0_SB_DQ<19>")
		)
		(pad "270" smd rect
			(at 2.050034 48.02505 90)
			(size 0.519938 1.4986)
			(layers "F.Cu" "F.Mask" "F.Paste")
			(net "GND")
		)
		(pad "271" smd rect
			(at 2.050034 48.874934 90)
			(size 0.519938 1.4986)
			(layers "F.Cu" "F.Mask" "F.Paste")
			(net "M_E_CPU0_SB_DQS_DN<7>")
		)
		(pad "272" smd rect
			(at 2.050034 49.725072 90)
			(size 0.519938 1.4986)
			(layers "F.Cu" "F.Mask" "F.Paste")
			(net "M_E_CPU0_SB_DQS_DP<7>")
		)
		(pad "273" smd rect
			(at 2.050034 50.574956 90)
			(size 0.519938 1.4986)
			(layers "F.Cu" "F.Mask" "F.Paste")
			(net "GND")
		)
		(pad "274" smd rect
			(at 2.050034 51.425094 90)
			(size 0.519938 1.4986)
			(layers "F.Cu" "F.Mask" "F.Paste")
			(net "M_E_CPU0_SB_DQ<22>")
		)
		(pad "275" smd rect
			(at 2.050034 52.274978 90)
			(size 0.519938 1.4986)
			(layers "F.Cu" "F.Mask" "F.Paste")
			(net "GND")
		)
		(pad "276" smd rect
			(at 2.050034 53.125116 90)
			(size 0.519938 1.4986)
			(layers "F.Cu" "F.Mask" "F.Paste")
			(net "M_E_CPU0_SB_DQ<23>")
		)
	)
)
